# S9S_MB_2U (Grand Teton) — schematic netlist excerpt (pin names and nets, part order shuffled) for the footprints in the layout excerpt that follows; sources: Cadence DE-HDL packaged netlist, KiCad conversion of 03242023_DA0F0TMBIJ0_F0T_Motherboard_J_brd_V01_OCP.brd

R3155  Q_RES  1K 1% CHIP  pkg 0402LF  page 164 : A = P3V3_AUX ; B = HP_LVC3_OCP_V3_2_PRSNT2
PC1848  Q_CAP  1UF 25V 10% X6S  pkg C0402  page 258 : A = P5V_AUX_VCC ; B = GND

(kicad_pcb
	(version 20260206)
	(generator "pcbnew")
	(generator_version "10.0")
	(general
		(thickness 1.6)
		(legacy_teardrops no)
	)
	(paper "A4")
	(title_block
		(title "03242023_DA0F0TMBIJ0_F0T_Motherboard_J_brd_V01_OCP.brd")
		(comment 1 "Grand Teton / footprints 1365-1366 of 6105")
	)
	(layers
		(0 "F.Cu" signal "TOP")
		(4 "In1.Cu" signal "GND")
		(6 "In2.Cu" signal "IN1")
		(8 "In3.Cu" signal "GND1")
		(10 "In4.Cu" signal "IN2")
		(12 "In5.Cu" signal "GND2")
		(14 "In6.Cu" signal "IN3")
		(16 "In7.Cu" signal "GND3")
		(18 "In8.Cu" signal "VCC")
		(20 "In9.Cu" signal "VCC1")
		(22 "In10.Cu" signal "GND4")
		(24 "In11.Cu" signal "IN4")
		(26 "In12.Cu" signal "GND5")
		(28 "In13.Cu" signal "IN5")
		(30 "In14.Cu" signal "GND6")
		(32 "In15.Cu" signal "IN6")
		(34 "In16.Cu" signal "GND7")
		(2 "B.Cu" signal "BOTTOM")
		(9 "F.Adhes" user "F.Adhesive")
		(11 "B.Adhes" user "B.Adhesive")
		(13 "F.Paste" user "Package Geometry/Pastemask Top")
		(15 "B.Paste" user "Package Geometry/Pastemask Bottom")
		(5 "F.SilkS" user "Ref Des/Silkscreen Top")
		(7 "B.SilkS" user "Ref Des/Silkscreen Bottom")
		(1 "F.Mask" user "Board Geometry/Soldermask Top")
		(3 "B.Mask" user "Board Geometry/Soldermask Bottom")
		(17 "Dwgs.User" user "User.Drawings")
		(19 "Cmts.User" user "User.Comments")
		(21 "Eco1.User" user "User.Eco1")
		(23 "Eco2.User" user "User.Eco2")
		(25 "Edge.Cuts" user "Board Geometry/Outline")
		(27 "Margin" user)
		(31 "F.CrtYd" user "Package Geometry/Place Bound Top")
		(29 "B.CrtYd" user "Package Geometry/Place Bound Bottom")
		(35 "F.Fab" user "Ref Des/Assembly Top")
		(33 "B.Fab" user "Ref Des/Assembly Bottom")
	)
	(footprint ""
		(layer "F.Cu")
		(at 456.444858 -387.950964)
		(property "Reference" "PC1848"
			(at 0 0 0)
			(layer "F.SilkS")
			(hide yes)
			(effects
				(font
					(size 1.27 1.27)
				)
			)
		)
		(property "Value" ""
			(at 0 0 0)
			(layer "F.Fab")
			(effects
				(font
					(size 1.27 1.27)
				)
			)
		)
		(duplicate_pad_numbers_are_jumpers no)
		(fp_line
			(start -0.7874 -0.4064)
			(end 0.7874 -0.4064)
			(stroke
				(width 0.1524)
				(type default)
			)
			(layer "F.SilkS")
		)
		(fp_line
			(start -0.7874 0.4064)
			(end -0.7874 -0.4064)
			(stroke
				(width 0.1524)
				(type default)
			)
			(layer "F.SilkS")
		)
		(fp_line
			(start 0.7874 -0.4064)
			(end 0.7874 0.4064)
			(stroke
				(width 0.1524)
				(type default)
			)
			(layer "F.SilkS")
		)
		(fp_line
			(start 0.7874 0.4064)
			(end -0.7874 0.4064)
			(stroke
				(width 0.1524)
				(type default)
			)
			(layer "F.SilkS")
		)
		(fp_line
			(start -0.67945 -0.305054)
			(end -0.12065 -0.305054)
			(stroke
				(width 0.1)
				(type default)
			)
			(layer "F.Fab")
		)
		(fp_line
			(start -0.67945 0.3048)
			(end -0.67945 -0.305054)
			(stroke
				(width 0.1)
				(type default)
			)
			(layer "F.Fab")
		)
		(fp_line
			(start -0.12065 -0.305054)
			(end -0.12065 -0.2794)
			(stroke
				(width 0.1)
				(type default)
			)
			(layer "F.Fab")
		)
		(fp_line
			(start -0.12065 -0.2794)
			(end 0.12065 -0.2794)
			(stroke
				(width 0.1)
				(type default)
			)
			(layer "F.Fab")
		)
		(fp_line
			(start -0.12065 0.2794)
			(end -0.12065 0.3048)
			(stroke
				(width 0.1)
				(type default)
			)
			(layer "F.Fab")
		)
		(fp_line
			(start -0.12065 0.3048)
			(end -0.67945 0.3048)
			(stroke
				(width 0.1)
				(type default)
			)
			(layer "F.Fab")
		)
		(fp_line
			(start 0.120396 0.2794)
			(end -0.12065 0.2794)
			(stroke
				(width 0.1)
				(type default)
			)
			(layer "F.Fab")
		)
		(fp_line
			(start 0.120396 0.3048)
			(end 0.120396 0.2794)
			(stroke
				(width 0.1)
				(type default)
			)
			(layer "F.Fab")
		)
		(fp_line
			(start 0.12065 -0.3048)
			(end 0.67945 -0.3048)
			(stroke
				(width 0.1)
				(type default)
			)
			(layer "F.Fab")
		)
		(fp_line
			(start 0.12065 -0.2794)
			(end 0.12065 -0.3048)
			(stroke
				(width 0.1)
				(type default)
			)
			(layer "F.Fab")
		)
		(fp_line
			(start 0.67945 -0.3048)
			(end 0.67945 0.3048)
			(stroke
				(width 0.1)
				(type default)
			)
			(layer "F.Fab")
		)
		(fp_line
			(start 0.67945 0.3048)
			(end 0.120396 0.3048)
			(stroke
				(width 0.1)
				(type default)
			)
			(layer "F.Fab")
		)
		(pad "1" smd circle
			(at -0.40005 0)
			(size 0 0)
			(layers "F.Cu" "F.Mask" "F.Paste")
			(net "P5V_AUX_VCC")
		)
		(pad "2" smd circle
			(at 0.40005 0)
			(size 0 0)
			(layers "F.Cu" "F.Mask" "F.Paste")
			(net "GND")
		)
	)
	(footprint ""
		(layer "F.Cu")
		(at 131.32308 -122.542808 -90)
		(property "Reference" "R3155"
			(at 0 0 270)
			(layer "F.SilkS")
			(hide yes)
			(effects
				(font
					(size 1.27 1.27)
				)
			)
		)
		(property "Value" ""
			(at 0 0 270)
			(layer "F.Fab")
			(effects
				(font
					(size 1.27 1.27)
				)
			)
		)
		(duplicate_pad_numbers_are_jumpers no)
		(fp_line
			(start -0.7874 0.4064)
			(end -0.7874 -0.4064)
			(stroke
				(width 0.1524)
				(type default)
			)
			(layer "F.SilkS")
		)
		(fp_line
			(start 0.7874 0.4064)
			(end -0.7874 0.4064)
			(stroke
				(width 0.1524)
				(type default)
			)
			(layer "F.SilkS")
		)
		(fp_line
			(start -0.7874 -0.4064)
			(end 0.7874 -0.4064)
			(stroke
				(width 0.1524)
				(type default)
			)
			(layer "F.SilkS")
		)
		(fp_line
			(start 0.7874 -0.4064)
			(end 0.7874 0.4064)
			(stroke
				(width 0.1524)
				(type default)
			)
			(layer "F.SilkS")
		)
		(fp_line
			(start -0.67945 0.3048)
			(end -0.67945 -0.305054)
			(stroke
				(width 0.1)
				(type default)
			)
			(layer "F.Fab")
		)
		(fp_line
			(start -0.12065 0.3048)
			(end -0.67945 0.3048)
			(stroke
				(width 0.1)
				(type default)
			)
			(layer "F.Fab")
		)
		(fp_line
			(start 0.120396 0.3048)
			(end 0.120396 0.2794)
			(stroke
				(width 0.1)
				(type default)
			)
			(layer "F.Fab")
		)
		(fp_line
			(start 0.67945 0.3048)
			(end 0.120396 0.3048)
			(stroke
				(width 0.1)
				(type default)
			)
			(layer "F.Fab")
		)
		(fp_line
			(start -0.12065 0.2794)
			(end -0.12065 0.3048)
			(stroke
				(width 0.1)
				(type default)
			)
			(layer "F.Fab")
		)
		(fp_line
			(start 0.120396 0.2794)
			(end -0.12065 0.2794)
			(stroke
				(width 0.1)
				(type default)
			)
			(layer "F.Fab")
		)
		(fp_line
			(start -0.12065 -0.2794)
			(end 0.12065 -0.2794)
			(stroke
				(width 0.1)
				(type default)
			)
			(layer "F.Fab")
		)
		(fp_line
			(start 0.12065 -0.2794)
			(end 0.12065 -0.3048)
			(stroke
				(width 0.1)
				(type default)
			)
			(layer "F.Fab")
		)
		(fp_line
			(start 0.12065 -0.3048)
			(end 0.67945 -0.3048)
			(stroke
				(width 0.1)
				(type default)
			)
			(layer "F.Fab")
		)
		(fp_line
			(start 0.67945 -0.3048)
			(end 0.67945 0.3048)
			(stroke
				(width 0.1)
				(type default)
			)
			(layer "F.Fab")
		)
		(fp_line
			(start -0.67945 -0.305054)
			(end -0.12065 -0.305054)
			(stroke
				(width 0.1)
				(type default)
			)
			(layer "F.Fab")
		)
		(fp_line
			(start -0.12065 -0.305054)
			(end -0.12065 -0.2794)
			(stroke
				(width 0.1)
				(type default)
			)
			(layer "F.Fab")
		)
		(pad "1" smd circle
			(at -0.40005 0 270)
			(size 0 0)
			(layers "F.Cu" "F.Mask" "F.Paste")
			(net "P3V3_AUX")
		)
		(pad "2" smd circle
			(at 0.40005 0 270)
			(size 0 0)
			(layers "F.Cu" "F.Mask" "F.Paste")
			(net "HP_LVC3_OCP_V3_2_PRSNT2")
		)
	)
)
